(kicad_pcb
	(version 20260206)
	(generator "pcbnew")
	(generator_version "10.0")
	(general
		(thickness 1.6)
		(legacy_teardrops no)
	)
	(paper "A4")
	(title_block
		(title "12092022_DA0F0TMDCD0_F0T_Management_Board_D_brd_V3_OCP.brd")
		(comment 1 "Grand Teton / footprints 721-726 of 1440")
	)
	(layers
		(0 "F.Cu" signal "TOP")
		(4 "In1.Cu" signal "GND")
		(6 "In2.Cu" signal "IN1")
		(8 "In3.Cu" signal "GND1")
		(10 "In4.Cu" signal "IN2")
		(12 "In5.Cu" signal "VCC")
		(14 "In6.Cu" signal "VCC1")
		(16 "In7.Cu" signal "IN3")
		(18 "In8.Cu" signal "GND2")
		(20 "In9.Cu" signal "IN4")
		(22 "In10.Cu" signal "GND3")
		(2 "B.Cu" signal "BOTTOM")
		(9 "F.Adhes" user "F.Adhesive")
		(11 "B.Adhes" user "B.Adhesive")
		(13 "F.Paste" user "Package Geometry/Pastemask Top")
		(15 "B.Paste" user "Package Geometry/Pastemask Bottom")
		(5 "F.SilkS" user "Ref Des/Silkscreen Top")
		(7 "B.SilkS" user "Ref Des/Silkscreen Bottom")
		(1 "F.Mask" user "Board Geometry/Soldermask Top")
		(3 "B.Mask" user "Board Geometry/Soldermask Bottom")
		(17 "Dwgs.User" user "User.Drawings")
		(19 "Cmts.User" user "User.Comments")
		(21 "Eco1.User" user "User.Eco1")
		(23 "Eco2.User" user "User.Eco2")
		(25 "Edge.Cuts" user "Board Geometry/Outline")
		(27 "Margin" user)
		(31 "F.CrtYd" user "Package Geometry/Place Bound Top")
		(29 "B.CrtYd" user "Package Geometry/Place Bound Bottom")
		(35 "F.Fab" user "Ref Des/Assembly Top")
		(33 "B.Fab" user "Ref Des/Assembly Bottom")
	)
	(footprint ""
		(layer "F.Cu")
		(at 81.788 -37.211 90)
		(property "Reference" "C153"
			(at 0 0 90)
			(layer "F.SilkS")
			(hide yes)
			(effects
				(font
					(size 1.27 1.27)
				)
			)
		)
		(property "Value" ""
			(at 0 0 90)
			(layer "F.Fab")
			(effects
				(font
					(size 1.27 1.27)
				)
			)
		)
		(duplicate_pad_numbers_are_jumpers no)
		(fp_line
			(start 0.7874 -0.4064)
			(end 0.7874 0.4064)
			(stroke
				(width 0.1524)
				(type default)
			)
			(layer "F.SilkS")
		)
		(fp_line
			(start -0.7874 -0.4064)
			(end 0.7874 -0.4064)
			(stroke
				(width 0.1524)
				(type default)
			)
			(layer "F.SilkS")
		)
		(fp_line
			(start 0.7874 0.4064)
			(end -0.7874 0.4064)
			(stroke
				(width 0.1524)
				(type default)
			)
			(layer "F.SilkS")
		)
		(fp_line
			(start -0.7874 0.4064)
			(end -0.7874 -0.4064)
			(stroke
				(width 0.1524)
				(type default)
			)
			(layer "F.SilkS")
		)
		(fp_line
			(start -0.12065 -0.305054)
			(end -0.12065 -0.2794)
			(stroke
				(width 0.1)
				(type default)
			)
			(layer "F.Fab")
		)
		(fp_line
			(start -0.67945 -0.305054)
			(end -0.12065 -0.305054)
			(stroke
				(width 0.1)
				(type default)
			)
			(layer "F.Fab")
		)
		(fp_line
			(start 0.67945 -0.3048)
			(end 0.67945 0.3048)
			(stroke
				(width 0.1)
				(type default)
			)
			(layer "F.Fab")
		)
		(fp_line
			(start 0.12065 -0.3048)
			(end 0.67945 -0.3048)
			(stroke
				(width 0.1)
				(type default)
			)
			(layer "F.Fab")
		)
		(fp_line
			(start 0.12065 -0.2794)
			(end 0.12065 -0.3048)
			(stroke
				(width 0.1)
				(type default)
			)
			(layer "F.Fab")
		)
		(fp_line
			(start -0.12065 -0.2794)
			(end 0.12065 -0.2794)
			(stroke
				(width 0.1)
				(type default)
			)
			(layer "F.Fab")
		)
		(fp_line
			(start 0.120396 0.2794)
			(end -0.12065 0.2794)
			(stroke
				(width 0.1)
				(type default)
			)
			(layer "F.Fab")
		)
		(fp_line
			(start -0.12065 0.2794)
			(end -0.12065 0.3048)
			(stroke
				(width 0.1)
				(type default)
			)
			(layer "F.Fab")
		)
		(fp_line
			(start 0.67945 0.3048)
			(end 0.120396 0.3048)
			(stroke
				(width 0.1)
				(type default)
			)
			(layer "F.Fab")
		)
		(fp_line
			(start 0.120396 0.3048)
			(end 0.120396 0.2794)
			(stroke
				(width 0.1)
				(type default)
			)
			(layer "F.Fab")
		)
		(fp_line
			(start -0.12065 0.3048)
			(end -0.67945 0.3048)
			(stroke
				(width 0.1)
				(type default)
			)
			(layer "F.Fab")
		)
		(fp_line
			(start -0.67945 0.3048)
			(end -0.67945 -0.305054)
			(stroke
				(width 0.1)
				(type default)
			)
			(layer "F.Fab")
		)
		(pad "1" smd circle
			(at -0.40005 0 90)
			(size 0 0)
			(layers "F.Cu" "F.Mask" "F.Paste")
			(net "PWRGD_P2V5_AUX_R")
		)
		(pad "2" smd circle
			(at 0.40005 0 90)
			(size 0 0)
			(layers "F.Cu" "F.Mask" "F.Paste")
			(net "GND")
		)
	)
	(footprint ""
		(layer "F.Cu")
		(at 84.201 -91.059)
		(property "Reference" "R408"
			(at 0 0 0)
			(layer "F.SilkS")
			(hide yes)
			(effects
				(font
					(size 1.27 1.27)
				)
			)
		)
		(property "Value" ""
			(at 0 0 0)
			(layer "F.Fab")
			(effects
				(font
					(size 1.27 1.27)
				)
			)
		)
		(duplicate_pad_numbers_are_jumpers no)
		(fp_line
			(start -0.7874 -0.4064)
			(end 0.7874 -0.4064)
			(stroke
				(width 0.1524)
				(type default)
			)
			(layer "F.SilkS")
		)
		(fp_line
			(start -0.7874 0.4064)
			(end -0.7874 -0.4064)
			(stroke
				(width 0.1524)
				(type default)
			)
			(layer "F.SilkS")
		)
		(fp_line
			(start 0.7874 -0.4064)
			(end 0.7874 0.4064)
			(stroke
				(width 0.1524)
				(type default)
			)
			(layer "F.SilkS")
		)
		(fp_line
			(start 0.7874 0.4064)
			(end -0.7874 0.4064)
			(stroke
				(width 0.1524)
				(type default)
			)
			(layer "F.SilkS")
		)
		(fp_line
			(start -0.67945 -0.305054)
			(end -0.12065 -0.305054)
			(stroke
				(width 0.1)
				(type default)
			)
			(layer "F.Fab")
		)
		(fp_line
			(start -0.67945 0.3048)
			(end -0.67945 -0.305054)
			(stroke
				(width 0.1)
				(type default)
			)
			(layer "F.Fab")
		)
		(fp_line
			(start -0.12065 -0.305054)
			(end -0.12065 -0.2794)
			(stroke
				(width 0.1)
				(type default)
			)
			(layer "F.Fab")
		)
		(fp_line
			(start -0.12065 -0.2794)
			(end 0.12065 -0.2794)
			(stroke
				(width 0.1)
				(type default)
			)
			(layer "F.Fab")
		)
		(fp_line
			(start -0.12065 0.2794)
			(end -0.12065 0.3048)
			(stroke
				(width 0.1)
				(type default)
			)
			(layer "F.Fab")
		)
		(fp_line
			(start -0.12065 0.3048)
			(end -0.67945 0.3048)
			(stroke
				(width 0.1)
				(type default)
			)
			(layer "F.Fab")
		)
		(fp_line
			(start 0.120396 0.2794)
			(end -0.12065 0.2794)
			(stroke
				(width 0.1)
				(type default)
			)
			(layer "F.Fab")
		)
		(fp_line
			(start 0.120396 0.3048)
			(end 0.120396 0.2794)
			(stroke
				(width 0.1)
				(type default)
			)
			(layer "F.Fab")
		)
		(fp_line
			(start 0.12065 -0.3048)
			(end 0.67945 -0.3048)
			(stroke
				(width 0.1)
				(type default)
			)
			(layer "F.Fab")
		)
		(fp_line
			(start 0.12065 -0.2794)
			(end 0.12065 -0.3048)
			(stroke
				(width 0.1)
				(type default)
			)
			(layer "F.Fab")
		)
		(fp_line
			(start 0.67945 -0.3048)
			(end 0.67945 0.3048)
			(stroke
				(width 0.1)
				(type default)
			)
			(layer "F.Fab")
		)
		(fp_line
			(start 0.67945 0.3048)
			(end 0.120396 0.3048)
			(stroke
				(width 0.1)
				(type default)
			)
			(layer "F.Fab")
		)
		(pad "1" smd circle
			(at -0.40005 0)
			(size 0 0)
			(layers "F.Cu" "F.Mask" "F.Paste")
			(net "P3V3_AUX")
		)
		(pad "2" smd circle
			(at 0.40005 0)
			(size 0 0)
			(layers "F.Cu" "F.Mask" "F.Paste")
			(net "SPI_BMC_TPM_CLK")
		)
	)
	(footprint ""
		(layer "F.Cu")
		(at 72.277732 -35.154362 180)
		(property "Reference" "C129"
			(at 0 0 180)
			(layer "F.SilkS")
			(hide yes)
			(effects
				(font
					(size 1.27 1.27)
				)
			)
		)
		(property "Value" ""
			(at 0 0 180)
			(layer "F.Fab")
			(effects
				(font
					(size 1.27 1.27)
				)
			)
		)
		(duplicate_pad_numbers_are_jumpers no)
		(fp_line
			(start 0.7874 0.4064)
			(end -0.7874 0.4064)
			(stroke
				(width 0.1524)
				(type default)
			)
			(layer "F.SilkS")
		)
		(fp_line
			(start 0.7874 -0.4064)
			(end 0.7874 0.4064)
			(stroke
				(width 0.1524)
				(type default)
			)
			(layer "F.SilkS")
		)
		(fp_line
			(start -0.7874 0.4064)
			(end -0.7874 -0.4064)
			(stroke
				(width 0.1524)
				(type default)
			)
			(layer "F.SilkS")
		)
		(fp_line
			(start -0.7874 -0.4064)
			(end 0.7874 -0.4064)
			(stroke
				(width 0.1524)
				(type default)
			)
			(layer "F.SilkS")
		)
		(fp_line
			(start 0.67945 0.3048)
			(end 0.120396 0.3048)
			(stroke
				(width 0.1)
				(type default)
			)
			(layer "F.Fab")
		)
		(fp_line
			(start 0.67945 -0.3048)
			(end 0.67945 0.3048)
			(stroke
				(width 0.1)
				(type default)
			)
			(layer "F.Fab")
		)
		(fp_line
			(start 0.12065 -0.2794)
			(end 0.12065 -0.3048)
			(stroke
				(width 0.1)
				(type default)
			)
			(layer "F.Fab")
		)
		(fp_line
			(start 0.12065 -0.3048)
			(end 0.67945 -0.3048)
			(stroke
				(width 0.1)
				(type default)
			)
			(layer "F.Fab")
		)
		(fp_line
			(start 0.120396 0.3048)
			(end 0.120396 0.2794)
			(stroke
				(width 0.1)
				(type default)
			)
			(layer "F.Fab")
		)
		(fp_line
			(start 0.120396 0.2794)
			(end -0.12065 0.2794)
			(stroke
				(width 0.1)
				(type default)
			)
			(layer "F.Fab")
		)
		(fp_line
			(start -0.12065 0.3048)
			(end -0.67945 0.3048)
			(stroke
				(width 0.1)
				(type default)
			)
			(layer "F.Fab")
		)
		(fp_line
			(start -0.12065 0.2794)
			(end -0.12065 0.3048)
			(stroke
				(width 0.1)
				(type default)
			)
			(layer "F.Fab")
		)
		(fp_line
			(start -0.12065 -0.2794)
			(end 0.12065 -0.2794)
			(stroke
				(width 0.1)
				(type default)
			)
			(layer "F.Fab")
		)
		(fp_line
			(start -0.12065 -0.305054)
			(end -0.12065 -0.2794)
			(stroke
				(width 0.1)
				(type default)
			)
			(layer "F.Fab")
		)
		(fp_line
			(start -0.67945 0.3048)
			(end -0.67945 -0.305054)
			(stroke
				(width 0.1)
				(type default)
			)
			(layer "F.Fab")
		)
		(fp_line
			(start -0.67945 -0.305054)
			(end -0.12065 -0.305054)
			(stroke
				(width 0.1)
				(type default)
			)
			(layer "F.Fab")
		)
		(pad "1" smd circle
			(at -0.40005 0 180)
			(size 0 0)
			(layers "F.Cu" "F.Mask" "F.Paste")
			(net "P1V2_AUX")
		)
		(pad "2" smd circle
			(at 0.40005 0 180)
			(size 0 0)
			(layers "F.Cu" "F.Mask" "F.Paste")
			(net "GND")
		)
	)
	(footprint ""
		(layer "F.Cu")
		(at 12.319 -85.344)
		(property "Reference" "R453"
			(at 0 0 0)
			(layer "F.SilkS")
			(hide yes)
			(effects
				(font
					(size 1.27 1.27)
				)
			)
		)
		(property "Value" ""
			(at 0 0 0)
			(layer "F.Fab")
			(effects
				(font
					(size 1.27 1.27)
				)
			)
		)
		(duplicate_pad_numbers_are_jumpers no)
		(fp_line
			(start -0.7874 -0.4064)
			(end 0.7874 -0.4064)
			(stroke
				(width 0.1524)
				(type default)
			)
			(layer "F.SilkS")
		)
		(fp_line
			(start -0.7874 0.4064)
			(end -0.7874 -0.4064)
			(stroke
				(width 0.1524)
				(type default)
			)
			(layer "F.SilkS")
		)
		(fp_line
			(start 0.7874 -0.4064)
			(end 0.7874 0.4064)
			(stroke
				(width 0.1524)
				(type default)
			)
			(layer "F.SilkS")
		)
		(fp_line
			(start 0.7874 0.4064)
			(end -0.7874 0.4064)
			(stroke
				(width 0.1524)
				(type default)
			)
			(layer "F.SilkS")
		)
		(fp_line
			(start -0.67945 -0.305054)
			(end -0.12065 -0.305054)
			(stroke
				(width 0.1)
				(type default)
			)
			(layer "F.Fab")
		)
		(fp_line
			(start -0.67945 0.3048)
			(end -0.67945 -0.305054)
			(stroke
				(width 0.1)
				(type default)
			)
			(layer "F.Fab")
		)
		(fp_line
			(start -0.12065 -0.305054)
			(end -0.12065 -0.2794)
			(stroke
				(width 0.1)
				(type default)
			)
			(layer "F.Fab")
		)
		(fp_line
			(start -0.12065 -0.2794)
			(end 0.12065 -0.2794)
			(stroke
				(width 0.1)
				(type default)
			)
			(layer "F.Fab")
		)
		(fp_line
			(start -0.12065 0.2794)
			(end -0.12065 0.3048)
			(stroke
				(width 0.1)
				(type default)
			)
			(layer "F.Fab")
		)
		(fp_line
			(start -0.12065 0.3048)
			(end -0.67945 0.3048)
			(stroke
				(width 0.1)
				(type default)
			)
			(layer "F.Fab")
		)
		(fp_line
			(start 0.120396 0.2794)
			(end -0.12065 0.2794)
			(stroke
				(width 0.1)
				(type default)
			)
			(layer "F.Fab")
		)
		(fp_line
			(start 0.120396 0.3048)
			(end 0.120396 0.2794)
			(stroke
				(width 0.1)
				(type default)
			)
			(layer "F.Fab")
		)
		(fp_line
			(start 0.12065 -0.3048)
			(end 0.67945 -0.3048)
			(stroke
				(width 0.1)
				(type default)
			)
			(layer "F.Fab")
		)
		(fp_line
			(start 0.12065 -0.2794)
			(end 0.12065 -0.3048)
			(stroke
				(width 0.1)
				(type default)
			)
			(layer "F.Fab")
		)
		(fp_line
			(start 0.67945 -0.3048)
			(end 0.67945 0.3048)
			(stroke
				(width 0.1)
				(type default)
			)
			(layer "F.Fab")
		)
		(fp_line
			(start 0.67945 0.3048)
			(end 0.120396 0.3048)
			(stroke
				(width 0.1)
				(type default)
			)
			(layer "F.Fab")
		)
		(pad "1" smd circle
			(at -0.40005 0)
			(size 0 0)
			(layers "F.Cu" "F.Mask" "F.Paste")
			(net "SMB_BMC_ALERT3_N")
		)
		(pad "2" smd circle
			(at 0.40005 0)
			(size 0 0)
			(layers "F.Cu" "F.Mask" "F.Paste")
			(net "SMB_BMC_ALERT3_R1_N")
		)
	)
	(footprint ""
		(layer "F.Cu")
		(at 112.014 -50.8 90)
		(property "Reference" "X5"
			(at -0.0508 5.50037 90)
			(unlocked yes)
			(layer "F.SilkS")
			(effects
				(font
					(size 0.7874 0.5842)
					(thickness 0.1524)
				)
				(justify left)
			)
		)
		(property "Value" ""
			(at 0 0 90)
			(layer "F.Fab")
			(effects
				(font
					(size 1.27 1.27)
				)
			)
		)
		(property "Device Type" "TP_TDR_4P_FTS_TH-TP_TDR_4P_DIPA"
			(at 1.30175 1.27 180)
			(unlocked yes)
			(layer "F.Fab")
			(hide yes)
			(effects
				(font
					(size 0.635 0.4064)
					(thickness 0.1524)
				)
			)
		)
		(property "User Part Number" "N_A"
			(at 1.30175 1.27 180)
			(unlocked yes)
			(layer "Cmts.User")
			(hide yes)
			(effects
				(font
					(size 0.635 0.4064)
					(thickness 0.1524)
				)
			)
		)
		(duplicate_pad_numbers_are_jumpers no)
		(fp_line
			(start 2.54 -1.27)
			(end 0 -1.27)
			(stroke
				(width 0.1524)
				(type default)
			)
			(layer "F.SilkS")
		)
		(fp_line
			(start 0 -1.27)
			(end 0 -0.635)
			(stroke
				(width 0.1524)
				(type default)
			)
			(layer "F.SilkS")
		)
		(fp_line
			(start 2.54 -1.1303)
			(end 2.54 -1.27)
			(stroke
				(width 0.1524)
				(type default)
			)
			(layer "F.SilkS")
		)
		(fp_line
			(start 0 0.635)
			(end 0 1.905)
			(stroke
				(width 0.1524)
				(type default)
			)
			(layer "F.SilkS")
		)
		(fp_line
			(start 2.54 1.4097)
			(end 2.54 1.1303)
			(stroke
				(width 0.1524)
				(type default)
			)
			(layer "F.SilkS")
		)
		(fp_line
			(start 0 3.175)
			(end 0 3.81)
			(stroke
				(width 0.1524)
				(type default)
			)
			(layer "F.SilkS")
		)
		(fp_line
			(start 2.54 3.81)
			(end 2.54 3.6703)
			(stroke
				(width 0.1524)
				(type default)
			)
			(layer "F.SilkS")
		)
		(fp_line
			(start 0 3.81)
			(end 2.54 3.81)
			(stroke
				(width 0.1524)
				(type default)
			)
			(layer "F.SilkS")
		)
		(fp_poly
			(pts
				(xy -0.761746 0) (xy -2.285746 -0.762) (xy -2.285746 0.762)
			)
			(stroke
				(width 0)
				(type default)
			)
			(fill yes)
			(layer "F.SilkS")
		)
		(fp_line
			(start 2.54 -1.27)
			(end 0 -1.27)
			(stroke
				(width 0.1)
				(type default)
			)
			(layer "F.Fab")
		)
		(fp_line
			(start 0 -1.27)
			(end 0 3.81)
			(stroke
				(width 0.1)
				(type default)
			)
			(layer "F.Fab")
		)
		(fp_line
			(start 2.54 3.81)
			(end 2.54 -1.27)
			(stroke
				(width 0.1)
				(type default)
			)
			(layer "F.Fab")
		)
		(fp_line
			(start 0 3.81)
			(end 2.54 3.81)
			(stroke
				(width 0.1)
				(type default)
			)
			(layer "F.Fab")
		)
		(fp_poly
			(pts
				(xy -0.761746 0) (xy -2.285746 -0.762) (xy -2.285746 0.762)
			)
			(stroke
				(width 0)
				(type default)
			)
			(fill yes)
			(layer "F.Fab")
		)
		(pad "1" thru_hole circle
			(at 0 0 90)
			(size 1.0033 1.0033)
			(drill 0.249936)
			(layers "*.Cu" "*.Mask")
			(remove_unused_layers no)
			(net "TDR_DIFF_85_IN4_DP")
			(clearance 0.10795)
			(thermal_gap 0.10795)
			(padstack
				(mode front_inner_back)
				(layer "Inner"
					(shape circle)
					(size 0.8001 0.8001)
					(clearance 0.1524)
				)
				(layer "B.Cu"
					(shape circle)
					(size 1.0033 1.0033)
					(clearance 0.10795)
				)
			)
		)
		(pad "2" thru_hole circle
			(at 2.54 0 90)
			(size 1.9939 1.9939)
			(drill 0.249936)
			(layers "*.Cu" "*.Mask")
			(remove_unused_layers no)
			(net "GND_P1")
			(clearance 0.10795)
			(thermal_gap 0.10795)
			(padstack
				(mode front_inner_back)
				(layer "Inner"
					(shape circle)
					(size 0.8001 0.8001)
					(clearance 0.1524)
				)
				(layer "B.Cu"
					(shape circle)
					(size 1.9939 1.9939)
					(clearance 0.10795)
				)
			)
		)
		(pad "3" thru_hole circle
			(at 2.54 2.54 90)
			(size 1.9939 1.9939)
			(drill 0.249936)
			(layers "*.Cu" "*.Mask")
			(remove_unused_layers no)
			(net "GND_P1")
			(clearance 0.10795)
			(thermal_gap 0.10795)
			(padstack
				(mode front_inner_back)
				(layer "Inner"
					(shape circle)
					(size 0.8001 0.8001)
					(clearance 0.1524)
				)
				(layer "B.Cu"
					(shape circle)
					(size 1.9939 1.9939)
					(clearance 0.10795)
				)
			)
		)
		(pad "4" thru_hole circle
			(at 0 2.54 90)
			(size 1.0033 1.0033)
			(drill 0.249936)
			(layers "*.Cu" "*.Mask")
			(remove_unused_layers no)
			(net "TDR_DIFF_85_IN4_DN")
			(clearance 0.10795)
			(thermal_gap 0.10795)
			(padstack
				(mode front_inner_back)
				(layer "Inner"
					(shape circle)
					(size 0.8001 0.8001)
					(clearance 0.1524)
				)
				(layer "B.Cu"
					(shape circle)
					(size 1.0033 1.0033)
					(clearance 0.10795)
				)
			)
		)
	)
	(footprint ""
		(layer "F.Cu")
		(at 32.70504 -70.536054 90)
		(property "Reference" "R653"
			(at 0 0 90)
			(layer "F.SilkS")
			(hide yes)
			(effects
				(font
					(size 1.27 1.27)
				)
			)
		)
		(property "Value" ""
			(at 0 0 90)
			(layer "F.Fab")
			(effects
				(font
					(size 1.27 1.27)
				)
			)
		)
		(duplicate_pad_numbers_are_jumpers no)
		(fp_line
			(start 0.7874 -0.4064)
			(end 0.7874 0.4064)
			(stroke
				(width 0.1524)
				(type default)
			)
			(layer "F.SilkS")
		)
		(fp_line
			(start -0.7874 -0.4064)
			(end 0.7874 -0.4064)
			(stroke
				(width 0.1524)
				(type default)
			)
			(layer "F.SilkS")
		)
		(fp_line
			(start 0.7874 0.4064)
			(end -0.7874 0.4064)
			(stroke
				(width 0.1524)
				(type default)
			)
			(layer "F.SilkS")
		)
		(fp_line
			(start -0.7874 0.4064)
			(end -0.7874 -0.4064)
			(stroke
				(width 0.1524)
				(type default)
			)
			(layer "F.SilkS")
		)
		(fp_line
			(start -0.12065 -0.305054)
			(end -0.12065 -0.2794)
			(stroke
				(width 0.1)
				(type default)
			)
			(layer "F.Fab")
		)
		(fp_line
			(start -0.67945 -0.305054)
			(end -0.12065 -0.305054)
			(stroke
				(width 0.1)
				(type default)
			)
			(layer "F.Fab")
		)
		(fp_line
			(start 0.67945 -0.3048)
			(end 0.67945 0.3048)
			(stroke
				(width 0.1)
				(type default)
			)
			(layer "F.Fab")
		)
		(fp_line
			(start 0.12065 -0.3048)
			(end 0.67945 -0.3048)
			(stroke
				(width 0.1)
				(type default)
			)
			(layer "F.Fab")
		)
		(fp_line
			(start 0.12065 -0.2794)
			(end 0.12065 -0.3048)
			(stroke
				(width 0.1)
				(type default)
			)
			(layer "F.Fab")
		)
		(fp_line
			(start -0.12065 -0.2794)
			(end 0.12065 -0.2794)
			(stroke
				(width 0.1)
				(type default)
			)
			(layer "F.Fab")
		)
		(fp_line
			(start 0.120396 0.2794)
			(end -0.12065 0.2794)
			(stroke
				(width 0.1)
				(type default)
			)
			(layer "F.Fab")
		)
		(fp_line
			(start -0.12065 0.2794)
			(end -0.12065 0.3048)
			(stroke
				(width 0.1)
				(type default)
			)
			(layer "F.Fab")
		)
		(fp_line
			(start 0.67945 0.3048)
			(end 0.120396 0.3048)
			(stroke
				(width 0.1)
				(type default)
			)
			(layer "F.Fab")
		)
		(fp_line
			(start 0.120396 0.3048)
			(end 0.120396 0.2794)
			(stroke
				(width 0.1)
				(type default)
			)
			(layer "F.Fab")
		)
		(fp_line
			(start -0.12065 0.3048)
			(end -0.67945 0.3048)
			(stroke
				(width 0.1)
				(type default)
			)
			(layer "F.Fab")
		)
		(fp_line
			(start -0.67945 0.3048)
			(end -0.67945 -0.305054)
			(stroke
				(width 0.1)
				(type default)
			)
			(layer "F.Fab")
		)
		(pad "1" smd circle
			(at -0.40005 0 90)
			(size 0 0)
			(layers "F.Cu" "F.Mask" "F.Paste")
			(net "BMC_EMMC_DT4")
		)
		(pad "2" smd circle
			(at 0.40005 0 90)
			(size 0 0)
			(layers "F.Cu" "F.Mask" "F.Paste")
			(net "EMMC_DT4_R")
		)
	)
)
